P  UNITS CUST 0
C   
C   vSure IPC 356 OUTPUT.  
C
C   FTP Site : valor.com
C   WEB Site : http://www.valor.com 
C
P   NNAME00000     I2C_C_BUF_SCL_CONN                                       
P   NNAME00001     I2C_C_BUF_SDA_CONN                                       
P   NNAME00002     PEER_TRAY_PRESENT                                        
P   NNAME00003     SD_LATCH_RELEASE                                         
P   NNAME00004     SELF_TRAY_PRESENT                                        
P   NNAME00005     STRADDLE_I2C_C_SDA                                       
P   NNAME00006     STRADDLE_I2C_C_SCL                                       
P   NNAME00007     TRAY_PRESENT_OUT_NET_B                                   
P   NNAME00008     TRAY_PRESENT_OUT#_C                                      
P   NNAME00009     I2C_C_BUF_SCLOUT                                         
P   NNAME00010     I2C_C_BUF_SDAOUT                                         
P   NNAME00011     I2C_C_BUF_READY                                          
P   NNAME00012     TRAY_PRESENT_OUT_NET                                     
P   NNAME00013     I2C_C_BUF_SCLIN                                          
P   NNAME00014     I2C_C_BUF_SDAIN                                          
317$NONE$                       D1580PA00X+060071Y+013691               S0      
317$NONE$                       D1580PA00X+060071Y+031191               S0      
317$NONE$                       D0400PA01X-002362Y+006279               S0      
317$NONE$                       D0400PA01X-002362Y+091627               S0      
317$NONE$                       D0400PA01X+129770Y+005847               S0      
317P3V3                         D0220PA01X+005535Y+039077               S0      
317P3V3                         D0220PA01X+004833Y+035245               S0      
317P3V3                         D0220PA01X+005109Y+039073               S0      
327P3V3                               A01X+004990Y+037965X0160Y0600     S0      
317P3V3                         D0240PA01X+004131Y+038746               S0      
317P3V3                         D0220PA01X+005271Y+035240               S0      
317P3V3                         D0340PA01X+004581Y+038807               S0      
327P3V3                               A04X-002756Y+030720X1970Y0320     S0      
327P3V3                               A04X-002756Y+031220X1970Y0320     S0      
317P3V3                         D0340PA01X+061280Y+040864               S0      
317P3V3                         D0220PA01X+053800Y+029670               S0      
317P3V3                         D0220PA01X+006005Y+039069               S0      
327P3V3                               A01X+060710Y+034380X0740Y1220     S0      
317P3V3                         D0220PA01X+052280Y+032600               S0      
317P3V3                         D0220PA01X+005740Y+035246               S0      
317P3V3             VIA        MD0280PA04X+002040Y+030994               S0      
317P3V3             VIA        MD0280PA04X+004940Y+032644               S0      
317P3V3             VIA        MD0280PA04X+005340Y+038894               S0      
317P3V3             VIA        MD0280PA04X+057950Y+033350               S0      
317P3V3             VIA        MD0280PA04X+060540Y+040944               S0      
317P3V3             VIA        MD0160PA00X+003750Y+038650               S0      
317P3V3             VIA        MD0160PA00X+004833Y+034851               S0      
317P3V3             VIA        MD0160PA00X+005109Y+039448               S0      
317P3V3             VIA        MD0160PA00X+052050Y+033100               S0      
317P3V3             VIA        MD0160PA00X+005271Y+034863               S0      
317P3V3             VIA        MD0160PA00X+054390Y+031400               S0      
317P3V3             VIA        MD0160PA00X+005535Y+039467               S0      
317P3V3             VIA        MD0160PA00X+005740Y+034868               S0      
317P3V3             VIA        MD0160PA00X+059550Y+033750               S0      
317P3V3             VIA        MD0160PA00X+059550Y+034200               S0      
317P3V3             VIA        MD0160PA00X+006005Y+039467               S0      
317P3V3             VIA        MD0160PA00X+060000Y+033750               S0      
317P3V3             VIA        MD0160PA00X+060000Y+034200               S0      
317P3V3             VIA        MD0160PA00X+061280Y+041300               S0      
317GND                          D0300PA01X+052516Y+031585               S0      
327GND                                A01X+055050Y+032234X0550Y0450     S0      
317GND                          D0480PA00X+060378Y+044213               S0      
317GND                          D0480PA00X+055949Y+042756               S0      
317GND                          D1400PA00X+003016Y+006102               S0      
327GND                                A01X+005758Y+036335X0160Y0600     S0      
317GND                          D0240PA01X+004131Y+039106               S0      
317GND                          D0220PA01X+054430Y+041900               S0      
317GND                          D1580PA00X+051835Y+044882               S0      
327GND                                A01X+047290Y+019024X0550Y0450     S0      
317GND                          D0340PA01X+004581Y+039367               S0      
327GND                                A01X+043500Y+019230X1100Y0550     S0      
317GND                          D1400PA00X+003016Y+041535               S0      
317GND                          D0340PA01X+054250Y+025817               S0      
327GND                                A04X-002501Y+021342X2480Y3720     S0      
327GND                                A04X-002201Y+022272X0010Y0010     S0      
327GND                                A04X-002201Y+021342X0010Y0010     S0      
327GND                                A04X-002201Y+020412X0010Y0010     S0      
327GND                                A04X-002501Y+025342X2480Y3720     S0      
327GND                                A04X-002201Y+026272X0010Y0010     S0      
327GND                                A04X-002201Y+025342X0010Y0010     S0      
327GND                                A04X-002201Y+024412X0010Y0010     S0      
327GND                                A04X-002501Y+028307X2480Y1650     S0      
327GND                                A04X-002201Y+028307X0010Y0010     S0      
327GND                                A01X-002501Y+028307X2480Y1650     S0      
327GND                                A01X-002651Y+028307X0010Y0010     S0      
327GND                                A01X-002501Y+025342X2480Y3720     S0      
327GND                                A01X-002651Y+026272X0010Y0010     S0      
327GND                                A01X-002651Y+025342X0010Y0010     S0      
327GND                                A01X-002651Y+024412X0010Y0010     S0      
327GND                                A01X-002501Y+021342X2480Y3720     S0      
327GND                                A01X-002651Y+022272X0010Y0010     S0      
327GND                                A01X-002651Y+021342X0010Y0010     S0      
327GND                                A01X-002651Y+020412X0010Y0010     S0      
327GND                                A04X-002756Y+030220X1970Y0320     S0      
327GND                                A04X-002756Y+033720X1970Y0320     S0      
327GND                                A04X-002756Y+034720X1970Y0320     S0      
327GND                                A04X-002756Y+035720X1970Y0320     S0      
327GND                                A01X-002756Y+035720X1970Y0320     S0      
327GND                                A01X-002756Y+032720X1970Y0320     S0      
327GND                                A01X-002756Y+031220X1970Y0320     S0      
327GND                                A01X-002756Y+030720X1970Y0320     S0      
317GND                          D0300PA01X+052514Y+030076               S0      
327GND                                A01X+051299Y+019816X0950Y0900     S0      
327GND                                A01X+042150Y+019230X1100Y0550     S0      
317GND                          D0340PA01X+003811Y+036313               S0      
327GND                                A01X+053814Y+019818X0950Y0900     S0      
317GND                          D0340PA01X+063449Y+007760               S0      
327GND                                A01X+046200Y+019230X1100Y0550     S0      
327GND                                A01X+044850Y+019230X1100Y0550     S0      
327GND                                A01X+000930Y+019742X0550Y0450     S0      
317GND                          D0410PA00X+060071Y+021441               S0      
317GND                          D0410PA00X+060071Y+023441               S0      
317GND                          D0410PA00X+059071Y+020441               S0      
317GND                          D0410PA00X+059071Y+022441               S0      
317GND                          D0410PA00X+059071Y+024441               S0      
317GND                          D0410PA00X+060071Y+025693               S0      
317GND                          D0410PA00X+059071Y+025693               S0      
317GND                          D0410PA00X+058071Y+025693               S0      
317GND                          D0410PA00X+057071Y+025693               S0      
317GND                          D0410PA00X+060071Y+026693               S0      
317GND                          D0410PA00X+059071Y+026693               S0      
317GND                          D0410PA00X+058071Y+026693               S0      
317GND                          D0410PA00X+057071Y+026693               S0      
317GND                          D0410PA00X+060071Y+027693               S0      
317GND                          D0410PA00X+059071Y+027693               S0      
317GND                          D0410PA00X+058071Y+027693               S0      
317GND                          D0410PA00X+057071Y+027693               S0      
317GND                          D0410PA00X+060071Y+028693               S0      
317GND                          D0410PA00X+059071Y+028693               S0      
317GND                          D0410PA00X+058071Y+028693               S0      
317GND                          D0410PA00X+057071Y+028693               S0      
327GND                                A01X+000020Y+019742X0550Y0450     S0      
327GND                                A01X+048763Y+019809X0950Y0900     S0      
317GND                          D1580PA00X+049866Y+002362               S0      
317GND                          D0340PA01X+003813Y+037993               S0      
317GND                          D0340PA01X+054250Y+027477               S0      
317GND                          D0220PA01X+053364Y+032640               S0      
317GND              VIA        MD0280PA04X+011440Y+030894               S0      
317GND              VIA        MD0280PA04X+020840Y+043344               S0      
317GND              VIA        MD0280PA04X+024790Y+023494               S0      
317GND              VIA        MD0280PA04X+024890Y+003594               S0      
317GND              VIA        MD0280PA04X+028240Y+031244               S0      
317GND              VIA        MD0280PA04X+036440Y+043094               S0      
317GND              VIA        MD0280PA04X+036540Y+003594               S0      
317GND              VIA        MD0280PA04X+039324Y+023999               S0      
317GND              VIA        MD0280PA04X+039402Y+030826               S0      
317GND              VIA        MD0280PA04X+044450Y+044500               S0      
317GND              VIA        MD0280PA04X+004740Y+021494               S0      
317GND              VIA        MD0280PA04X+047750Y+037050               S0      
317GND              VIA        MD0280PA04X+004840Y+027494               S0      
317GND              VIA        MD0280PA04X+050650Y+041850               S0      
317GND              VIA        MD0280PA04X+050740Y+019644               S0      
317GND              VIA        MD0280PA04X+052590Y+003344               S0      
317GND              VIA        MD0280PA04X+053490Y+026144               S0      
317GND              VIA        MD0280PA04X+054300Y+019750               S0      
317GND              VIA        MD0280PA04X+056869Y+006641               S0      
317GND              VIA        MD0280PA04X+006740Y+041694               S0      
317GND              VIA        MD0280PA04X+007600Y+003200               S0      
317GND              VIA        MD0280PA04X+007840Y+037194               S0      
317GND              VIA        MD0160PA00X-000260Y+020694               S0      
317GND              VIA        MD0160PA00X-000260Y+021694               S0      
317GND              VIA        MD0160PA00X-000260Y+022694               S0      
317GND              VIA        MD0160PA00X-000260Y+023694               S0      
317GND              VIA        MD0160PA00X-000260Y+024694               S0      
317GND              VIA        MD0160PA00X-000260Y+025694               S0      
317GND              VIA        MD0160PA00X-000260Y+026694               S0      
317GND              VIA        MD0160PA00X-000260Y+027694               S0      
317GND              VIA        MD0160PA00X-000260Y+031644               S0      
317GND              VIA        MD0160PA00X-000295Y+030220               S0      
317GND              VIA        MD0160PA00X-000660Y+034720               S0      
317GND              VIA        MD0160PA00X-000660Y+035720               S0      
317GND              VIA        MD0160PA00X-000694Y+031625               S0      
317GND              VIA        MD0160PA00X-000710Y+032720               S0      
317GND              VIA        MD0160PA00X-000710Y+033720               S0      
317GND              VIA        MD0160PA00X+010533Y+044296               S0      
317GND              VIA        MD0160PA00X+011533Y+033796               S0      
317GND              VIA        MD0160PA00X+011533Y+035796               S0      
317GND              VIA        MD0160PA00X+011533Y+037796               S0      
317GND              VIA        MD0160PA00X+011533Y+041796               S0      
317GND              VIA        MD0160PA00X+011640Y+026694               S0      
317GND              VIA        MD0160PA00X+011640Y+028694               S0      
317GND              VIA        MD0160PA00X+011642Y+004648               S0      
317GND              VIA        MD0160PA00X+011740Y+020694               S0      
317GND              VIA        MD0160PA00X+011740Y+022694               S0      
317GND              VIA        MD0160PA00X+011740Y+024694               S0      
317GND              VIA        MD0160PA00X+011750Y+046550               S0      
317GND              VIA        MD0160PA00X+013200Y+044250               S0      
317GND              VIA        MD0160PA00X+013533Y+033796               S0      
317GND              VIA        MD0160PA00X+013533Y+035796               S0      
317GND              VIA        MD0160PA00X+013533Y+037796               S0      
317GND              VIA        MD0160PA00X+013533Y+041796               S0      
317GND              VIA        MD0160PA00X+013642Y+004648               S0      
317GND              VIA        MD0160PA00X+013642Y+000648               S0      
317GND              VIA        MD0160PA00X+013740Y+020694               S0      
317GND              VIA        MD0160PA00X+013740Y+022694               S0      
317GND              VIA        MD0160PA00X+013740Y+024694               S0      
317GND              VIA        MD0160PA00X+013740Y+026694               S0      
317GND              VIA        MD0160PA00X+013740Y+028694               S0      
317GND              VIA        MD0160PA00X+013990Y+046544               S0      
317GND              VIA        MD0160PA00X+015500Y+044200               S0      
317GND              VIA        MD0160PA00X+015533Y+033796               S0      
317GND              VIA        MD0160PA00X+015533Y+035796               S0      
317GND              VIA        MD0160PA00X+015533Y+037796               S0      
317GND              VIA        MD0160PA00X+015533Y+041796               S0      
317GND              VIA        MD0160PA00X+015642Y+002648               S0      
317GND              VIA        MD0160PA00X+015642Y+004648               S0      
317GND              VIA        MD0160PA00X+015642Y+000648               S0      
317GND              VIA        MD0160PA00X+015740Y+020694               S0      
317GND              VIA        MD0160PA00X+015740Y+022694               S0      
317GND              VIA        MD0160PA00X+015740Y+024694               S0      
317GND              VIA        MD0160PA00X+015740Y+026694               S0      
317GND              VIA        MD0160PA00X+015740Y+028694               S0      
317GND              VIA        MD0160PA00X+015990Y+046544               S0      
317GND              VIA        MD0160PA00X+001642Y+002648               S0      
317GND              VIA        MD0160PA00X+001642Y+000648               S0      
317GND              VIA        MD0160PA00X+001740Y+020694               S0      
317GND              VIA        MD0160PA00X+001740Y+021694               S0      
317GND              VIA        MD0160PA00X+001740Y+025694               S0      
317GND              VIA        MD0160PA00X+001740Y+026694               S0      
317GND              VIA        MD0160PA00X+001740Y+027694               S0      
317GND              VIA        MD0160PA00X+001740Y+028694               S0      
317GND              VIA        MD0160PA00X+017533Y+033796               S0      
317GND              VIA        MD0160PA00X+017533Y+035796               S0      
317GND              VIA        MD0160PA00X+017533Y+037796               S0      
317GND              VIA        MD0160PA00X+017533Y+041796               S0      
317GND              VIA        MD0160PA00X+017550Y+044200               S0      
317GND              VIA        MD0160PA00X+017642Y+002648               S0      
317GND              VIA        MD0160PA00X+017642Y+004648               S0      
317GND              VIA        MD0160PA00X+017642Y+000648               S0      
317GND              VIA        MD0160PA00X+017740Y+020644               S0      
317GND              VIA        MD0160PA00X+017740Y+022694               S0      
317GND              VIA        MD0160PA00X+017740Y+024694               S0      
317GND              VIA        MD0160PA00X+017740Y+026694               S0      
317GND              VIA        MD0160PA00X+017740Y+028694               S0      
317GND              VIA        MD0160PA00X+017990Y+046544               S0      
317GND              VIA        MD0160PA00X+019533Y+033796               S0      
317GND              VIA        MD0160PA00X+019533Y+035796               S0      
317GND              VIA        MD0160PA00X+019533Y+037796               S0      
317GND              VIA        MD0160PA00X+019533Y+041796               S0      
317GND              VIA        MD0160PA00X+019600Y+044250               S0      
317GND              VIA        MD0160PA00X+019642Y+002648               S0      
317GND              VIA        MD0160PA00X+019642Y+004648               S0      
317GND              VIA        MD0160PA00X+019642Y+000648               S0      
317GND              VIA        MD0160PA00X+019740Y+020644               S0      
317GND              VIA        MD0160PA00X+019740Y+022694               S0      
317GND              VIA        MD0160PA00X+019740Y+024694               S0      
317GND              VIA        MD0160PA00X+019740Y+026694               S0      
317GND              VIA        MD0160PA00X+019740Y+028694               S0      
317GND              VIA        MD0160PA00X+001990Y+046544               S0      
317GND              VIA        MD0160PA00X+019990Y+046544               S0      
317GND              VIA        MD0160PA00X+021533Y+033796               S0      
317GND              VIA        MD0160PA00X+021533Y+035796               S0      
317GND              VIA        MD0160PA00X+021533Y+037796               S0      
317GND              VIA        MD0160PA00X+021533Y+041796               S0      
317GND              VIA        MD0160PA00X+021583Y+044246               S0      
317GND              VIA        MD0160PA00X+021642Y+002648               S0      
317GND              VIA        MD0160PA00X+021642Y+004648               S0      
317GND              VIA        MD0160PA00X+021642Y+000648               S0      
317GND              VIA        MD0160PA00X+021740Y+020644               S0      
317GND              VIA        MD0160PA00X+021740Y+022694               S0      
317GND              VIA        MD0160PA00X+021740Y+024694               S0      
317GND              VIA        MD0160PA00X+021740Y+026694               S0      
317GND              VIA        MD0160PA00X+021740Y+028694               S0      
317GND              VIA        MD0160PA00X+021990Y+046544               S0      
317GND              VIA        MD0160PA00X+002200Y+037450               S0      
317GND              VIA        MD0160PA00X+002200Y+038750               S0      
317GND              VIA        MD0160PA00X+023533Y+033796               S0      
317GND              VIA        MD0160PA00X+023533Y+035796               S0      
317GND              VIA        MD0160PA00X+023533Y+037796               S0      
317GND              VIA        MD0160PA00X+023533Y+041796               S0      
317GND              VIA        MD0160PA00X+023583Y+044246               S0      
317GND              VIA        MD0160PA00X+023642Y+002648               S0      
317GND              VIA        MD0160PA00X+023642Y+004648               S0      
317GND              VIA        MD0160PA00X+023642Y+000648               S0      
317GND              VIA        MD0160PA00X+023740Y+020644               S0      
317GND              VIA        MD0160PA00X+023740Y+022694               S0      
317GND              VIA        MD0160PA00X+023740Y+024694               S0      
317GND              VIA        MD0160PA00X+023740Y+026694               S0      
317GND              VIA        MD0160PA00X+023740Y+028694               S0      
317GND              VIA        MD0160PA00X+023990Y+046544               S0      
317GND              VIA        MD0160PA00X+002500Y+034300               S0      
317GND              VIA        MD0160PA00X+002550Y+035300               S0      
317GND              VIA        MD0160PA00X+025533Y+033796               S0      
317GND              VIA        MD0160PA00X+025533Y+035796               S0      
317GND              VIA        MD0160PA00X+025533Y+037796               S0      
317GND              VIA        MD0160PA00X+025533Y+041796               S0      
317GND              VIA        MD0160PA00X+025583Y+044246               S0      
317GND              VIA        MD0160PA00X+025642Y+002648               S0      
317GND              VIA        MD0160PA00X+025642Y+004648               S0      
317GND              VIA        MD0160PA00X+025642Y+000648               S0      
317GND              VIA        MD0160PA00X+025740Y+020644               S0      
317GND              VIA        MD0160PA00X+025740Y+022694               S0      
317GND              VIA        MD0160PA00X+025740Y+024694               S0      
317GND              VIA        MD0160PA00X+025740Y+026694               S0      
317GND              VIA        MD0160PA00X+025740Y+028694               S0      
317GND              VIA        MD0160PA00X+025990Y+046544               S0      
317GND              VIA        MD0160PA00X+002740Y+020694               S0      
317GND              VIA        MD0160PA00X+002740Y+021694               S0      
317GND              VIA        MD0160PA00X+002740Y+025694               S0      
317GND              VIA        MD0160PA00X+002740Y+026694               S0      
317GND              VIA        MD0160PA00X+002740Y+027694               S0      
317GND              VIA        MD0160PA00X+002740Y+028694               S0      
317GND              VIA        MD0160PA00X+027533Y+033796               S0      
317GND              VIA        MD0160PA00X+027533Y+035796               S0      
317GND              VIA        MD0160PA00X+027533Y+037796               S0      
317GND              VIA        MD0160PA00X+027533Y+041796               S0      
317GND              VIA        MD0160PA00X+027583Y+044246               S0      
317GND              VIA        MD0160PA00X+027642Y+002648               S0      
317GND              VIA        MD0160PA00X+027642Y+004648               S0      
317GND              VIA        MD0160PA00X+027642Y+000648               S0      
317GND              VIA        MD0160PA00X+027740Y+020644               S0      
317GND              VIA        MD0160PA00X+027740Y+022694               S0      
317GND              VIA        MD0160PA00X+027740Y+024694               S0      
317GND              VIA        MD0160PA00X+027740Y+026694               S0      
317GND              VIA        MD0160PA00X+027940Y+028694               S0      
317GND              VIA        MD0160PA00X+027990Y+046544               S0      
317GND              VIA        MD0160PA00X+029533Y+033796               S0      
317GND              VIA        MD0160PA00X+029533Y+035796               S0      
317GND              VIA        MD0160PA00X+029533Y+037796               S0      
317GND              VIA        MD0160PA00X+029533Y+041796               S0      
317GND              VIA        MD0160PA00X+029583Y+044246               S0      
317GND              VIA        MD0160PA00X+029642Y+002648               S0      
317GND              VIA        MD0160PA00X+029642Y+004648               S0      
317GND              VIA        MD0160PA00X+029642Y+000648               S0      
317GND              VIA        MD0160PA00X+029740Y+020644               S0      
317GND              VIA        MD0160PA00X+029740Y+022694               S0      
317GND              VIA        MD0160PA00X+029740Y+024694               S0      
317GND              VIA        MD0160PA00X+029740Y+026694               S0      
317GND              VIA        MD0160PA00X+029990Y+046544               S0      
317GND              VIA        MD0160PA00X+030040Y+028694               S0      
317GND              VIA        MD0160PA00X+031533Y+033796               S0      
317GND              VIA        MD0160PA00X+031533Y+035796               S0      
317GND              VIA        MD0160PA00X+031533Y+037796               S0      
317GND              VIA        MD0160PA00X+031533Y+041796               S0      
317GND              VIA        MD0160PA00X+031583Y+044246               S0      
317GND              VIA        MD0160PA00X+031642Y+002648               S0      
317GND              VIA        MD0160PA00X+031642Y+004648               S0      
317GND              VIA        MD0160PA00X+031642Y+000648               S0      
317GND              VIA        MD0160PA00X+031740Y+020644               S0      
317GND              VIA        MD0160PA00X+031740Y+022694               S0      
317GND              VIA        MD0160PA00X+031740Y+024694               S0      
317GND              VIA        MD0160PA00X+031740Y+026694               S0      
317GND              VIA        MD0160PA00X+031740Y+028694               S0      
317GND              VIA        MD0160PA00X+031990Y+046544               S0      
317GND              VIA        MD0160PA00X+033533Y+033796               S0      
317GND              VIA        MD0160PA00X+033533Y+035796               S0      
317GND              VIA        MD0160PA00X+033533Y+037796               S0      
317GND              VIA        MD0160PA00X+033533Y+041796               S0      
317GND              VIA        MD0160PA00X+033583Y+044246               S0      
317GND              VIA        MD0160PA00X+033642Y+002648               S0      
317GND              VIA        MD0160PA00X+033642Y+004648               S0      
317GND              VIA        MD0160PA00X+033642Y+000648               S0      
317GND              VIA        MD0160PA00X+033740Y+020644               S0      
317GND              VIA        MD0160PA00X+033740Y+022694               S0      
317GND              VIA        MD0160PA00X+033740Y+024694               S0      
317GND              VIA        MD0160PA00X+033740Y+026694               S0      
317GND              VIA        MD0160PA00X+033740Y+028694               S0      
317GND              VIA        MD0160PA00X+003399Y+036293               S0      
317GND              VIA        MD0160PA00X+033990Y+046544               S0      
317GND              VIA        MD0160PA00X+003490Y+034494               S0      
317GND              VIA        MD0160PA00X+035533Y+033796               S0      
317GND              VIA        MD0160PA00X+035533Y+035796               S0      
317GND              VIA        MD0160PA00X+035533Y+037796               S0      
317GND              VIA        MD0160PA00X+035533Y+041796               S0      
317GND              VIA        MD0160PA00X+035583Y+044246               S0      
317GND              VIA        MD0160PA00X+035642Y+002648               S0      
317GND              VIA        MD0160PA00X+035642Y+004648               S0      
317GND              VIA        MD0160PA00X+035642Y+000648               S0      
317GND              VIA        MD0160PA00X+035740Y+020644               S0      
317GND              VIA        MD0160PA00X+035740Y+022694               S0      
317GND              VIA        MD0160PA00X+035740Y+024694               S0      
317GND              VIA        MD0160PA00X+035740Y+026694               S0      
317GND              VIA        MD0160PA00X+035740Y+028694               S0      
317GND              VIA        MD0160PA00X+003583Y+044246               S0      
317GND              VIA        MD0160PA00X+035990Y+046544               S0      
317GND              VIA        MD0160PA00X+003642Y+002648               S0      
317GND              VIA        MD0160PA00X+003642Y+000648               S0      
317GND              VIA        MD0160PA00X+003677Y+022694               S0      
317GND              VIA        MD0160PA00X+003677Y+024694               S0      
317GND              VIA        MD0160PA00X+003740Y+020694               S0      
317GND              VIA        MD0160PA00X+003740Y+026694               S0      
317GND              VIA        MD0160PA00X+003740Y+028694               S0      
317GND              VIA        MD0160PA00X+037533Y+033796               S0      
317GND              VIA        MD0160PA00X+037533Y+035796               S0      
317GND              VIA        MD0160PA00X+037533Y+037796               S0      
317GND              VIA        MD0160PA00X+037533Y+041796               S0      
317GND              VIA        MD0160PA00X+037583Y+044246               S0      
317GND              VIA        MD0160PA00X+037642Y+002648               S0      
317GND              VIA        MD0160PA00X+037642Y+004648               S0      
317GND              VIA        MD0160PA00X+037642Y+000648               S0      
317GND              VIA        MD0160PA00X+037740Y+020644               S0      
317GND              VIA        MD0160PA00X+037740Y+022694               S0      
317GND              VIA        MD0160PA00X+037740Y+024694               S0      
317GND              VIA        MD0160PA00X+037740Y+026694               S0      
317GND              VIA        MD0160PA00X+037740Y+028694               S0      
317GND              VIA        MD0160PA00X+037990Y+046544               S0      
317GND              VIA        MD0160PA00X+039533Y+033796               S0      
317GND              VIA        MD0160PA00X+039533Y+035796               S0      
317GND              VIA        MD0160PA00X+039533Y+037796               S0      
317GND              VIA        MD0160PA00X+039533Y+041796               S0      
317GND              VIA        MD0160PA00X+039583Y+044246               S0      
317GND              VIA        MD0160PA00X+039642Y+002648               S0      
317GND              VIA        MD0160PA00X+039642Y+004648               S0      
317GND              VIA        MD0160PA00X+039642Y+000648               S0      
317GND              VIA        MD0160PA00X+039740Y+020644               S0      
317GND              VIA        MD0160PA00X+039740Y+022694               S0      
317GND              VIA        MD0160PA00X+039740Y+024694               S0      
317GND              VIA        MD0160PA00X+039740Y+026694               S0      
317GND              VIA        MD0160PA00X+039740Y+028694               S0      
317GND              VIA        MD0160PA00X+003990Y+046544               S0      
317GND              VIA        MD0160PA00X+039990Y+046544               S0      
317GND              VIA        MD0160PA00X+041533Y+033796               S0      
317GND              VIA        MD0160PA00X+041533Y+035796               S0      
317GND              VIA        MD0160PA00X+041533Y+037796               S0      
317GND              VIA        MD0160PA00X+041533Y+041796               S0      
317GND              VIA        MD0160PA00X+041583Y+044246               S0      
317GND              VIA        MD0160PA00X+041642Y+002648               S0      
317GND              VIA        MD0160PA00X+041642Y+004648               S0      
317GND              VIA        MD0160PA00X+041642Y+000648               S0      
317GND              VIA        MD0160PA00X+041740Y+020644               S0      
317GND              VIA        MD0160PA00X+041740Y+022694               S0      
317GND              VIA        MD0160PA00X+041740Y+024694               S0      
317GND              VIA        MD0160PA00X+041830Y+019750               S0      
317GND              VIA        MD0160PA00X+041830Y+020170               S0      
317GND              VIA        MD0160PA00X+041840Y+026694               S0      
317GND              VIA        MD0160PA00X+041840Y+028694               S0      
317GND              VIA        MD0160PA00X+041990Y+046544               S0      
317GND              VIA        MD0160PA00X+042250Y+019750               S0      
317GND              VIA        MD0160PA00X+042250Y+020170               S0      
317GND              VIA        MD0160PA00X+042670Y+019750               S0      
317GND              VIA        MD0160PA00X+042670Y+020170               S0      
317GND              VIA        MD0160PA00X+043130Y+019750               S0      
317GND              VIA        MD0160PA00X+043130Y+020170               S0      
317GND              VIA        MD0160PA00X+043533Y+041796               S0      
317GND              VIA        MD0160PA00X+043540Y+033844               S0      
317GND              VIA        MD0160PA00X+043540Y+035844               S0      
317GND              VIA        MD0160PA00X+043540Y+037844               S0      
317GND              VIA        MD0160PA00X+043550Y+019750               S0      
317GND              VIA        MD0160PA00X+043550Y+020170               S0      
317GND              VIA        MD0160PA00X+043583Y+044246               S0      
317GND              VIA        MD0160PA00X+043642Y+004648               S0      
317GND              VIA        MD0160PA00X+043642Y+000648               S0      
317GND              VIA        MD0160PA00X+043740Y+020644               S0      
317GND              VIA        MD0160PA00X+043740Y+022694               S0      
317GND              VIA        MD0160PA00X+043740Y+024694               S0      
317GND              VIA        MD0160PA00X+043740Y+026694               S0      
317GND              VIA        MD0160PA00X+043740Y+028694               S0      
317GND              VIA        MD0160PA00X+043970Y+019750               S0      
317GND              VIA        MD0160PA00X+043970Y+020170               S0      
317GND              VIA        MD0160PA00X+043990Y+046544               S0      
317GND              VIA        MD0160PA00X+044480Y+019750               S0      
317GND              VIA        MD0160PA00X+044480Y+020170               S0      
317GND              VIA        MD0160PA00X+044900Y+019750               S0      
317GND              VIA        MD0160PA00X+044900Y+020170               S0      
317GND              VIA        MD0160PA00X+045320Y+019750               S0      
317GND              VIA        MD0160PA00X+045320Y+020170               S0      
317GND              VIA        MD0160PA00X+045450Y+046550               S0      
317GND              VIA        MD0160PA00X+045533Y+041796               S0      
317GND              VIA        MD0160PA00X+045540Y+033844               S0      
317GND              VIA        MD0160PA00X+045540Y+035844               S0      
317GND              VIA        MD0160PA00X+045540Y+037844               S0      
317GND              VIA        MD0160PA00X+045642Y+004648               S0      
317GND              VIA        MD0160PA00X+045740Y+020644               S0      
317GND              VIA        MD0160PA00X+045740Y+022694               S0      
317GND              VIA        MD0160PA00X+045740Y+024694               S0      
317GND              VIA        MD0160PA00X+045740Y+026694               S0      
317GND              VIA        MD0160PA00X+045740Y+028694               S0      
317GND              VIA        MD0160PA00X+045780Y+019750               S0      
317GND              VIA        MD0160PA00X+045780Y+020170               S0      
317GND              VIA        MD0160PA00X+046200Y+019750               S0      
317GND              VIA        MD0160PA00X+046200Y+020170               S0      
317GND              VIA        MD0160PA00X+046620Y+019750               S0      
317GND              VIA        MD0160PA00X+046620Y+020170               S0      
317GND              VIA        MD0160PA00X+046650Y+042800               S0      
317GND              VIA        MD0160PA00X+047289Y+019697               S0      
317GND              VIA        MD0160PA00X+047289Y+020117               S0      
317GND              VIA        MD0160PA00X+047540Y+033844               S0      
317GND              VIA        MD0160PA00X+047540Y+035844               S0      
317GND              VIA        MD0160PA00X+047540Y+037844               S0      
317GND              VIA        MD0160PA00X+047642Y+004648               S0      
317GND              VIA        MD0160PA00X+047700Y+041800               S0      
317GND              VIA        MD0160PA00X+047709Y+019697               S0      
317GND              VIA        MD0160PA00X+047709Y+020117               S0      
317GND              VIA        MD0160PA00X+047740Y+022694               S0      
317GND              VIA        MD0160PA00X+047740Y+024694               S0      
317GND              VIA        MD0160PA00X+047740Y+026694               S0      
317GND              VIA        MD0160PA00X+048031Y+020660               S0      
317GND              VIA        MD0160PA00X+048031Y+021080               S0      
317GND              VIA        MD0160PA00X+048451Y+020660               S0      
317GND              VIA        MD0160PA00X+048451Y+021080               S0      
317GND              VIA        MD0160PA00X+048871Y+020660               S0      
317GND              VIA        MD0160PA00X+048871Y+021080               S0      
317GND              VIA        MD0160PA00X+049200Y+032100               S0      
317GND              VIA        MD0160PA00X+049291Y+020660               S0      
317GND              VIA        MD0160PA00X+049291Y+021080               S0      
317GND              VIA        MD0160PA00X+049540Y+033844               S0      
317GND              VIA        MD0160PA00X+049540Y+035844               S0      
317GND              VIA        MD0160PA00X+049540Y+037844               S0      
317GND              VIA        MD0160PA00X+049642Y+004648               S0      
317GND              VIA        MD0160PA00X+049740Y+022694               S0      
317GND              VIA        MD0160PA00X+049740Y+024694               S0      
317GND              VIA        MD0160PA00X+049805Y+019619               S0      
317GND              VIA        MD0160PA00X+049805Y+020039               S0      
317GND              VIA        MD0160PA00X+049900Y+041850               S0      
317GND              VIA        MD0160PA00X+050225Y+019619               S0      
317GND              VIA        MD0160PA00X+050225Y+020039               S0      
317GND              VIA        MD0160PA00X+050614Y+020636               S0      
317GND              VIA        MD0160PA00X+050614Y+021056               S0      
317GND              VIA        MD0160PA00X+050650Y+030550               S0      
317GND              VIA        MD0160PA00X+051034Y+020636               S0      
317GND              VIA        MD0160PA00X+051034Y+021056               S0      
317GND              VIA        MD0160PA00X+051250Y+032300               S0      
317GND              VIA        MD0160PA00X+051454Y+020636               S0      
317GND              VIA        MD0160PA00X+051454Y+021056               S0      
317GND              VIA        MD0160PA00X+051642Y+004648               S0      
317GND              VIA        MD0160PA00X+051642Y+000648               S0      
317GND              VIA        MD0160PA00X+051874Y+020636               S0      
317GND              VIA        MD0160PA00X+051874Y+021056               S0      
317GND              VIA        MD0160PA00X+052038Y+030076               S0      
317GND              VIA        MD0160PA00X+052090Y+022844               S0      
317GND              VIA        MD0160PA00X+052356Y+019643               S0      
317GND              VIA        MD0160PA00X+052356Y+020063               S0      
317GND              VIA        MD0160PA00X+052516Y+031100               S0      
317GND              VIA        MD0160PA00X+052776Y+019643               S0      
317GND              VIA        MD0160PA00X+052776Y+020063               S0      
317GND              VIA        MD0160PA00X+053188Y+020619               S0      
317GND              VIA        MD0160PA00X+053188Y+021039               S0      
317GND              VIA        MD0160PA00X+053362Y+002648               S0      
317GND              VIA        MD0160PA00X+053362Y+004648               S0      
317GND              VIA        MD0160PA00X+053362Y+000648               S0      
317GND              VIA        MD0160PA00X+053400Y+028200               S0      
317GND              VIA        MD0160PA00X+053608Y+020619               S0      
317GND              VIA        MD0160PA00X+053608Y+021039               S0      
317GND              VIA        MD0160PA00X+053714Y+032640               S0      
317GND              VIA        MD0160PA00X+053800Y+046484               S0      
317GND              VIA        MD0160PA00X+054028Y+020619               S0      
317GND              VIA        MD0160PA00X+054028Y+021039               S0      
317GND              VIA        MD0160PA00X+054090Y+022844               S0      
317GND              VIA        MD0160PA00X+054448Y+020619               S0      
317GND              VIA        MD0160PA00X+054448Y+021039               S0      
317GND              VIA        MD0160PA00X+054660Y+025797               S0      
317GND              VIA        MD0160PA00X+054800Y+044250               S0      
317GND              VIA        MD0160PA00X+054897Y+019668               S0      
317GND              VIA        MD0160PA00X+054897Y+020088               S0      
317GND              VIA        MD0160PA00X+054950Y+030550               S0      
317GND              VIA        MD0160PA00X+055082Y+002648               S0      
317GND              VIA        MD0160PA00X+055082Y+004648               S0      
317GND              VIA        MD0160PA00X+055082Y+000648               S0      
317GND              VIA        MD0160PA00X+055300Y+042500               S0      
317GND              VIA        MD0160PA00X+055317Y+019668               S0      
317GND              VIA        MD0160PA00X+055317Y+020088               S0      
317GND              VIA        MD0160PA00X+005550Y+041700               S0      
317GND              VIA        MD0160PA00X+055642Y+006648               S0      
317GND              VIA        MD0160PA00X+056000Y+028297               S0      
317GND              VIA        MD0160PA00X+056050Y+026800               S0      
317GND              VIA        MD0160PA00X+056150Y+029800               S0      
317GND              VIA        MD0160PA00X+005642Y+004648               S0      
317GND              VIA        MD0160PA00X+056802Y+002648               S0      
317GND              VIA        MD0160PA00X+056802Y+004648               S0      
317GND              VIA        MD0160PA00X+056802Y+000648               S0      
317GND              VIA        MD0160PA00X+056850Y+046484               S0      
317GND              VIA        MD0160PA00X+005740Y+020694               S0      
317GND              VIA        MD0160PA00X+005740Y+022694               S0      
317GND              VIA        MD0160PA00X+005740Y+024694               S0      
317GND              VIA        MD0160PA00X+005740Y+026694               S0      
317GND              VIA        MD0160PA00X+005740Y+028694               S0      
317GND              VIA        MD0160PA00X+057362Y+006697               S0      
317GND              VIA        MD0160PA00X+057750Y+030500               S0      
317GND              VIA        MD0160PA00X+058454Y+008667               S0      
317GND              VIA        MD0160PA00X+058522Y+002648               S0      
317GND              VIA        MD0160PA00X+058522Y+004648               S0      
317GND              VIA        MD0160PA00X+058522Y+000648               S0      
317GND              VIA        MD0160PA00X+058750Y+031850               S0      
317GND              VIA        MD0160PA00X+059200Y+046484               S0      
317GND              VIA        MD0160PA00X+059450Y+011700               S0      
317GND              VIA        MD0160PA00X+060000Y+029850               S0      
317GND              VIA        MD0160PA00X+060242Y+002648               S0      
317GND              VIA        MD0160PA00X+060242Y+004648               S0      
317GND              VIA        MD0160PA00X+060242Y+000648               S0      
317GND              VIA        MD0160PA00X+060700Y+012350               S0      
317GND              VIA        MD0160PA00X+061090Y+042544               S0      
317GND              VIA        MD0160PA00X+061090Y+044544               S0      
317GND              VIA        MD0160PA00X+061090Y+046544               S0      
317GND              VIA        MD0160PA00X+061125Y+006570               S0      
317GND              VIA        MD0160PA00X+061140Y+008694               S0      
317GND              VIA        MD0160PA00X+061540Y+026644               S0      
317GND              VIA        MD0160PA00X+061540Y+028444               S0      
317GND              VIA        MD0160PA00X+061550Y+019900               S0      
317GND              VIA        MD0160PA00X+061590Y+022444               S0      
317GND              VIA        MD0160PA00X+061590Y+024444               S0      
317GND              VIA        MD0160PA00X+061600Y+011550               S0      
317GND              VIA        MD0160PA00X+061600Y+013800               S0      
317GND              VIA        MD0160PA00X+061600Y+017350               S0      
317GND              VIA        MD0160PA00X+061650Y+031624               S0      
317GND              VIA        MD0160PA00X+006190Y+035894               S0      
317GND              VIA        MD0160PA00X+061962Y+002648               S0      
317GND              VIA        MD0160PA00X+061962Y+004648               S0      
317GND              VIA        MD0160PA00X+061962Y+000648               S0      
317GND              VIA        MD0160PA00X+006200Y+044250               S0      
317GND              VIA        MD0160PA00X+006240Y+033844               S0      
317GND              VIA        MD0160PA00X+062650Y+007850               S0      
317GND              VIA        MD0160PA00X+062850Y+010400               S0      
317GND              VIA        MD0160PA00X+000640Y+036994               S0      
317GND              VIA        MD0160PA00X+063000Y+034550               S0      
317GND              VIA        MD0160PA00X+063000Y+038750               S0      
317GND              VIA        MD0160PA00X+063290Y+040494               S0      
317GND              VIA        MD0160PA00X+063290Y+042494               S0      
317GND              VIA        MD0160PA00X+063290Y+044494               S0      
317GND              VIA        MD0160PA00X+063290Y+046494               S0      
317GND              VIA        MD0160PA00X+063340Y+032544               S0      
317GND              VIA        MD0160PA00X+063375Y+006570               S0      
317GND              VIA        MD0160PA00X+063390Y+008694               S0      
317GND              VIA        MD0160PA00X+063400Y+012350               S0      
317GND              VIA        MD0160PA00X+063412Y+002648               S0      
317GND              VIA        MD0160PA00X+063412Y+004648               S0      
317GND              VIA        MD0160PA00X+063412Y+000648               S0      
317GND              VIA        MD0160PA00X+006440Y+030444               S0      
317GND              VIA        MD0160PA00X+006783Y+046546               S0      
317GND              VIA        MD0160PA00X+000690Y+038744               S0      
317GND              VIA        MD0160PA00X+000690Y+044544               S0      
317GND              VIA        MD0160PA00X+000690Y+046544               S0      
317GND              VIA        MD0160PA00X+000740Y+020694               S0      
317GND              VIA        MD0160PA00X+000740Y+021694               S0      
317GND              VIA        MD0160PA00X+000740Y+022694               S0      
317GND              VIA        MD0160PA00X+000740Y+023694               S0      
317GND              VIA        MD0160PA00X+000740Y+024694               S0      
317GND              VIA        MD0160PA00X+000740Y+025694               S0      
317GND              VIA        MD0160PA00X+000740Y+026694               S0      
317GND              VIA        MD0160PA00X+000740Y+027694               S0      
317GND              VIA        MD0160PA00X+000740Y+028694               S0      
317GND              VIA        MD0160PA00X+007550Y+041750               S0      
317GND              VIA        MD0160PA00X+007642Y+004648               S0      
317GND              VIA        MD0160PA00X+007740Y+020694               S0      
317GND              VIA        MD0160PA00X+007740Y+022694               S0      
317GND              VIA        MD0160PA00X+007740Y+024694               S0      
317GND              VIA        MD0160PA00X+007740Y+026694               S0      
317GND              VIA        MD0160PA00X+007740Y+028694               S0      
317GND              VIA        MD0160PA00X+007790Y+033844               S0      
317GND              VIA        MD0160PA00X+007840Y+035844               S0      
317GND              VIA        MD0160PA00X+008533Y+044296               S0      
317GND              VIA        MD0160PA00X+008640Y+030394               S0      
317GND              VIA        MD0160PA00X+009150Y+046550               S0      
317GND              VIA        MD0160PA00X+009533Y+035796               S0      
317GND              VIA        MD0160PA00X+009533Y+037796               S0      
317GND              VIA        MD0160PA00X+009533Y+041796               S0      
317GND              VIA        MD0160PA00X+009640Y+033794               S0      
317GND              VIA        MD0160PA00X+009642Y+004648               S0      
317GND              VIA        MD0160PA00X+009740Y+020694               S0      
317GND              VIA        MD0160PA00X+009740Y+022694               S0      
317GND              VIA        MD0160PA00X+009740Y+024694               S0      
317GND              VIA        MD0160PA00X+009740Y+026694               S0      
317GND              VIA        MD0160PA00X+009740Y+028694               S0      
327P12V                               A01X+047290Y+018264X0550Y0450     S0      
327P12V                               A01X+043500Y+018070X1100Y0550     S0      
327P12V                               A04X-002501Y+013342X2480Y3720     S0      
327P12V                               A04X-002201Y+014272X0010Y0010     S0      
327P12V                               A04X-002201Y+013342X0010Y0010     S0      
327P12V                               A04X-002201Y+012412X0010Y0010     S0      
327P12V                               A04X-002501Y+017342X2480Y3720     S0      
327P12V                               A04X-002201Y+018272X0010Y0010     S0      
327P12V                               A04X-002201Y+017342X0010Y0010     S0      
327P12V                               A04X-002201Y+016412X0010Y0010     S0      
327P12V                               A01X-002501Y+017342X2480Y3720     S0      
327P12V                               A01X-002651Y+018272X0010Y0010     S0      
327P12V                               A01X-002651Y+017342X0010Y0010     S0      
327P12V                               A01X-002651Y+016412X0010Y0010     S0      
327P12V                               A01X-002501Y+013342X2480Y3720     S0      
327P12V                               A01X-002651Y+014272X0010Y0010     S0      
327P12V                               A01X-002651Y+013342X0010Y0010     S0      
327P12V                               A01X-002651Y+012412X0010Y0010     S0      
327P12V                               A01X+051299Y+017336X0950Y0900     S0      
317P12V                         D0340PA01X+061800Y+007730               S0      
327P12V                               A01X+042150Y+018070X1100Y0550     S0      
327P12V                               A01X+053814Y+017338X0950Y0900     S0      
327P12V                               A01X+046200Y+018070X1100Y0550     S0      
327P12V                               A01X+044850Y+018070X1100Y0550     S0      
327P12V                               A01X+000930Y+018982X0550Y0450     S0      
317P12V                         D0410PA00X+060071Y+016189               S0      
317P12V                         D0410PA00X+059071Y+016189               S0      
317P12V                         D0410PA00X+058071Y+016189               S0      
317P12V                         D0410PA00X+057071Y+016189               S0      
317P12V                         D0410PA00X+060071Y+017189               S0      
317P12V                         D0410PA00X+059071Y+017189               S0      
317P12V                         D0410PA00X+058071Y+017189               S0      
317P12V                         D0410PA00X+057071Y+017189               S0      
317P12V                         D0410PA00X+060071Y+018189               S0      
317P12V                         D0410PA00X+059071Y+018189               S0      
317P12V                         D0410PA00X+058071Y+018189               S0      
317P12V                         D0410PA00X+057071Y+018189               S0      
317P12V                         D0410PA00X+060071Y+019189               S0      
317P12V                         D0410PA00X+059071Y+019189               S0      
317P12V                         D0410PA00X+058071Y+019189               S0      
317P12V                         D0410PA00X+057071Y+019189               S0      
327P12V                               A01X+000020Y+018982X0550Y0450     S0      
327P12V                               A01X+048763Y+017329X0950Y0900     S0      
317P12V             VIA        MD0280PA04X+018940Y+011594               S0      
317P12V             VIA        MD0280PA04X+034790Y+011744               S0      
317P12V             VIA        MD0280PA04X+004690Y+011794               S0      
317P12V             VIA        MD0280PA04X+004690Y+015294               S0      
317P12V             VIA        MD0280PA04X+004690Y+018294               S0      
317P12V             VIA        MD0280PA04X+052640Y+011694               S0      
317P12V             VIA        MD0280PA04X+007300Y+009450               S0      
317P12V             VIA        MD0160PA00X-000335Y+011750               S0      
317P12V             VIA        MD0160PA00X-000358Y+012648               S0      
317P12V             VIA        MD0160PA00X-000358Y+013648               S0      
317P12V             VIA        MD0160PA00X-000358Y+014648               S0      
317P12V             VIA        MD0160PA00X-000358Y+015648               S0      
317P12V             VIA        MD0160PA00X-000358Y+016648               S0      
317P12V             VIA        MD0160PA00X-000358Y+017648               S0      
317P12V             VIA        MD0160PA00X+011642Y+010648               S0      
317P12V             VIA        MD0160PA00X+011642Y+012648               S0      
317P12V             VIA        MD0160PA00X+011642Y+014648               S0      
317P12V             VIA        MD0160PA00X+011642Y+016648               S0      
317P12V             VIA        MD0160PA00X+011642Y+018648               S0      
317P12V             VIA        MD0160PA00X+011642Y+006648               S0      
317P12V             VIA        MD0160PA00X+011642Y+008648               S0      
317P12V             VIA        MD0160PA00X+013642Y+010648               S0      
317P12V             VIA        MD0160PA00X+013642Y+012648               S0      
317P12V             VIA        MD0160PA00X+013642Y+014648               S0      
317P12V             VIA        MD0160PA00X+013642Y+016648               S0      
317P12V             VIA        MD0160PA00X+013642Y+018648               S0      
317P12V             VIA        MD0160PA00X+013642Y+006648               S0      
317P12V             VIA        MD0160PA00X+013642Y+008648               S0      
317P12V             VIA        MD0160PA00X+015642Y+010648               S0      
317P12V             VIA        MD0160PA00X+015642Y+012648               S0      
317P12V             VIA        MD0160PA00X+015642Y+014648               S0      
317P12V             VIA        MD0160PA00X+015642Y+016648               S0      
317P12V             VIA        MD0160PA00X+015642Y+018648               S0      
317P12V             VIA        MD0160PA00X+015642Y+006648               S0      
317P12V             VIA        MD0160PA00X+015642Y+008648               S0      
317P12V             VIA        MD0160PA00X+001642Y+010648               S0      
317P12V             VIA        MD0160PA00X+001642Y+011648               S0      
317P12V             VIA        MD0160PA00X+001642Y+012648               S0      
317P12V             VIA        MD0160PA00X+001642Y+013648               S0      
317P12V             VIA        MD0160PA00X+001642Y+014648               S0      
317P12V             VIA        MD0160PA00X+001642Y+015648               S0      
317P12V             VIA        MD0160PA00X+001642Y+016648               S0      
317P12V             VIA        MD0160PA00X+001642Y+017648               S0      
317P12V             VIA        MD0160PA00X+001642Y+018648               S0      
317P12V             VIA        MD0160PA00X+001642Y+008648               S0      
317P12V             VIA        MD0160PA00X+017642Y+010648               S0      
317P12V             VIA        MD0160PA00X+017642Y+012648               S0      
317P12V             VIA        MD0160PA00X+017642Y+014648               S0      
317P12V             VIA        MD0160PA00X+017642Y+016648               S0      
317P12V             VIA        MD0160PA00X+017642Y+018648               S0      
317P12V             VIA        MD0160PA00X+017642Y+006648               S0      
317P12V             VIA        MD0160PA00X+017642Y+008648               S0      
317P12V             VIA        MD0160PA00X+019642Y+010648               S0      
317P12V             VIA        MD0160PA00X+019642Y+012648               S0      
317P12V             VIA        MD0160PA00X+019642Y+014648               S0      
317P12V             VIA        MD0160PA00X+019642Y+016648               S0      
317P12V             VIA        MD0160PA00X+019642Y+018648               S0      
317P12V             VIA        MD0160PA00X+019642Y+006648               S0      
317P12V             VIA        MD0160PA00X+019642Y+008648               S0      
317P12V             VIA        MD0160PA00X+021642Y+010648               S0      
317P12V             VIA        MD0160PA00X+021642Y+012648               S0      
317P12V             VIA        MD0160PA00X+021642Y+014648               S0      
317P12V             VIA        MD0160PA00X+021642Y+016648               S0      
317P12V             VIA        MD0160PA00X+021642Y+018648               S0      
317P12V             VIA        MD0160PA00X+021642Y+006648               S0      
317P12V             VIA        MD0160PA00X+021642Y+008648               S0      
317P12V             VIA        MD0160PA00X+023642Y+010648               S0      
317P12V             VIA        MD0160PA00X+023642Y+012648               S0      
317P12V             VIA        MD0160PA00X+023642Y+014648               S0      
317P12V             VIA        MD0160PA00X+023642Y+016648               S0      
317P12V             VIA        MD0160PA00X+023642Y+018648               S0      
317P12V             VIA        MD0160PA00X+023642Y+006648               S0      
317P12V             VIA        MD0160PA00X+023642Y+008648               S0      
317P12V             VIA        MD0160PA00X+025150Y+016650               S0      
317P12V             VIA        MD0160PA00X+025642Y+010648               S0      
317P12V             VIA        MD0160PA00X+025642Y+012648               S0      
317P12V             VIA        MD0160PA00X+025642Y+014648               S0      
317P12V             VIA        MD0160PA00X+025642Y+018648               S0      
317P12V             VIA        MD0160PA00X+025642Y+006648               S0      
317P12V             VIA        MD0160PA00X+025642Y+008648               S0      
317P12V             VIA        MD0160PA00X+002642Y+011648               S0      
317P12V             VIA        MD0160PA00X+002642Y+012648               S0      
317P12V             VIA        MD0160PA00X+002642Y+013648               S0      
317P12V             VIA        MD0160PA00X+002642Y+014648               S0      
317P12V             VIA        MD0160PA00X+002642Y+015648               S0      
317P12V             VIA        MD0160PA00X+002642Y+016648               S0      
317P12V             VIA        MD0160PA00X+002642Y+017648               S0      
317P12V             VIA        MD0160PA00X+002642Y+018648               S0      
317P12V             VIA        MD0160PA00X+027350Y+006650               S0      
317P12V             VIA        MD0160PA00X+027450Y+010650               S0      
317P12V             VIA        MD0160PA00X+027450Y+008650               S0      
317P12V             VIA        MD0160PA00X+027550Y+018650               S0      
317P12V             VIA        MD0160PA00X+027642Y+012648               S0      
317P12V             VIA        MD0160PA00X+027642Y+014648               S0      
317P12V             VIA        MD0160PA00X+027642Y+016648               S0      
317P12V             VIA        MD0160PA00X+029550Y+016900               S0      
317P12V             VIA        MD0160PA00X+029642Y+012648               S0      
317P12V             VIA        MD0160PA00X+029642Y+014648               S0      
317P12V             VIA        MD0160PA00X+029642Y+018648               S0      
317P12V             VIA        MD0160PA00X+030000Y+010650               S0      
317P12V             VIA        MD0160PA00X+030100Y+008650               S0      
317P12V             VIA        MD0160PA00X+030200Y+006700               S0      
317P12V             VIA        MD0160PA00X+031642Y+010648               S0      
317P12V             VIA        MD0160PA00X+031642Y+012648               S0      
317P12V             VIA        MD0160PA00X+031642Y+014648               S0      
317P12V             VIA        MD0160PA00X+031642Y+006648               S0      
317P12V             VIA        MD0160PA00X+031642Y+008648               S0      
317P12V             VIA        MD0160PA00X+031700Y+016650               S0      
317P12V             VIA        MD0160PA00X+031750Y+018650               S0      
317P12V             VIA        MD0160PA00X+033642Y+010648               S0      
317P12V             VIA        MD0160PA00X+033642Y+012648               S0      
317P12V             VIA        MD0160PA00X+033642Y+014648               S0      
317P12V             VIA        MD0160PA00X+033642Y+018648               S0      
317P12V             VIA        MD0160PA00X+033642Y+006648               S0      
317P12V             VIA        MD0160PA00X+033642Y+008648               S0      
317P12V             VIA        MD0160PA00X+033850Y+016600               S0      
317P12V             VIA        MD0160PA00X+035450Y+016650               S0      
317P12V             VIA        MD0160PA00X+035642Y+010648               S0      
317P12V             VIA        MD0160PA00X+035642Y+012648               S0      
317P12V             VIA        MD0160PA00X+035642Y+014648               S0      
317P12V             VIA        MD0160PA00X+035642Y+006648               S0      
317P12V             VIA        MD0160PA00X+035642Y+008648               S0      
317P12V             VIA        MD0160PA00X+035750Y+018650               S0      
317P12V             VIA        MD0160PA00X+003642Y+010648               S0      
317P12V             VIA        MD0160PA00X+003642Y+012648               S0      
317P12V             VIA        MD0160PA00X+003642Y+014648               S0      
317P12V             VIA        MD0160PA00X+003642Y+016648               S0      
317P12V             VIA        MD0160PA00X+003642Y+018648               S0      
317P12V             VIA        MD0160PA00X+003642Y+008648               S0      
317P12V             VIA        MD0160PA00X+037642Y+010648               S0      
317P12V             VIA        MD0160PA00X+037642Y+012648               S0      
317P12V             VIA        MD0160PA00X+037642Y+014648               S0      
317P12V             VIA        MD0160PA00X+037642Y+018648               S0      
317P12V             VIA        MD0160PA00X+037642Y+006648               S0      
317P12V             VIA        MD0160PA00X+037642Y+008648               S0      
317P12V             VIA        MD0160PA00X+038000Y+016650               S0      
317P12V             VIA        MD0160PA00X+039642Y+010648               S0      
317P12V             VIA        MD0160PA00X+039642Y+012648               S0      
317P12V             VIA        MD0160PA00X+039642Y+014648               S0      
317P12V             VIA        MD0160PA00X+039642Y+016648               S0      
317P12V             VIA        MD0160PA00X+039642Y+018648               S0      
317P12V             VIA        MD0160PA00X+039642Y+006648               S0      
317P12V             VIA        MD0160PA00X+039642Y+008648               S0      
317P12V             VIA        MD0160PA00X+041642Y+010648               S0      
317P12V             VIA        MD0160PA00X+041642Y+012648               S0      
317P12V             VIA        MD0160PA00X+041642Y+014648               S0      
317P12V             VIA        MD0160PA00X+041642Y+006648               S0      
317P12V             VIA        MD0160PA00X+041642Y+008648               S0      
317P12V             VIA        MD0160PA00X+041650Y+016600               S0      
317P12V             VIA        MD0160PA00X+041752Y+017028               S0      
317P12V             VIA        MD0160PA00X+041752Y+017448               S0      
317P12V             VIA        MD0160PA00X+042172Y+017028               S0      
317P12V             VIA        MD0160PA00X+042172Y+017448               S0      
317P12V             VIA        MD0160PA00X+042592Y+017028               S0      
317P12V             VIA        MD0160PA00X+042592Y+017448               S0      
317P12V             VIA        MD0160PA00X+043110Y+017030               S0      
317P12V             VIA        MD0160PA00X+043110Y+017450               S0      
317P12V             VIA        MD0160PA00X+043530Y+017030               S0      
317P12V             VIA        MD0160PA00X+043530Y+017450               S0      
317P12V             VIA        MD0160PA00X+043642Y+010648               S0      
317P12V             VIA        MD0160PA00X+043642Y+012648               S0      
317P12V             VIA        MD0160PA00X+043642Y+014648               S0      
317P12V             VIA        MD0160PA00X+043642Y+006648               S0      
317P12V             VIA        MD0160PA00X+043642Y+008648               S0      
317P12V             VIA        MD0160PA00X+043650Y+016600               S0      
317P12V             VIA        MD0160PA00X+043950Y+017030               S0      
317P12V             VIA        MD0160PA00X+043950Y+017450               S0      
317P12V             VIA        MD0160PA00X+044410Y+017030               S0      
317P12V             VIA        MD0160PA00X+044410Y+017450               S0      
317P12V             VIA        MD0160PA00X+044830Y+017030               S0      
317P12V             VIA        MD0160PA00X+044830Y+017450               S0      
317P12V             VIA        MD0160PA00X+045250Y+017030               S0      
317P12V             VIA        MD0160PA00X+045250Y+017450               S0      
317P12V             VIA        MD0160PA00X+045642Y+010648               S0      
317P12V             VIA        MD0160PA00X+045642Y+012648               S0      
317P12V             VIA        MD0160PA00X+045642Y+014648               S0      
317P12V             VIA        MD0160PA00X+045642Y+006648               S0      
317P12V             VIA        MD0160PA00X+045642Y+008648               S0      
317P12V             VIA        MD0160PA00X+045650Y+016650               S0      
317P12V             VIA        MD0160PA00X+045710Y+017080               S0      
317P12V             VIA        MD0160PA00X+045710Y+017500               S0      
317P12V             VIA        MD0160PA00X+046130Y+017080               S0      
317P12V             VIA        MD0160PA00X+046130Y+017500               S0      
317P12V             VIA        MD0160PA00X+046550Y+017080               S0      
317P12V             VIA        MD0160PA00X+046550Y+017500               S0      
317P12V             VIA        MD0160PA00X+047308Y+017039               S0      
317P12V             VIA        MD0160PA00X+047308Y+017459               S0      
317P12V             VIA        MD0160PA00X+047642Y+010648               S0      
317P12V             VIA        MD0160PA00X+047642Y+012648               S0      
317P12V             VIA        MD0160PA00X+047642Y+014648               S0      
317P12V             VIA        MD0160PA00X+047642Y+006648               S0      
317P12V             VIA        MD0160PA00X+047642Y+008648               S0      
317P12V             VIA        MD0160PA00X+047728Y+017039               S0      
317P12V             VIA        MD0160PA00X+047728Y+017459               S0      
317P12V             VIA        MD0160PA00X+048124Y+016067               S0      
317P12V             VIA        MD0160PA00X+048124Y+016487               S0      
317P12V             VIA        MD0160PA00X+048544Y+016067               S0      
317P12V             VIA        MD0160PA00X+048544Y+016487               S0      
317P12V             VIA        MD0160PA00X+048964Y+016067               S0      
317P12V             VIA        MD0160PA00X+048964Y+016487               S0      
317P12V             VIA        MD0160PA00X+049384Y+016067               S0      
317P12V             VIA        MD0160PA00X+049384Y+016487               S0      
317P12V             VIA        MD0160PA00X+049642Y+010648               S0      
317P12V             VIA        MD0160PA00X+049642Y+012648               S0      
317P12V             VIA        MD0160PA00X+049642Y+014648               S0      
317P12V             VIA        MD0160PA00X+049642Y+006648               S0      
317P12V             VIA        MD0160PA00X+049642Y+008648               S0      
317P12V             VIA        MD0160PA00X+049840Y+017049               S0      
317P12V             VIA        MD0160PA00X+049840Y+017469               S0      
317P12V             VIA        MD0160PA00X+050260Y+017049               S0      
317P12V             VIA        MD0160PA00X+050260Y+017469               S0      
317P12V             VIA        MD0160PA00X+050662Y+016091               S0      
317P12V             VIA        MD0160PA00X+050662Y+016511               S0      
317P12V             VIA        MD0160PA00X+051082Y+016091               S0      
317P12V             VIA        MD0160PA00X+051082Y+016511               S0      
317P12V             VIA        MD0160PA00X+051502Y+016091               S0      
317P12V             VIA        MD0160PA00X+051502Y+016511               S0      
317P12V             VIA        MD0160PA00X+051642Y+010648               S0      
317P12V             VIA        MD0160PA00X+051642Y+012648               S0      
317P12V             VIA        MD0160PA00X+051642Y+014648               S0      
317P12V             VIA        MD0160PA00X+051642Y+006648               S0      
317P12V             VIA        MD0160PA00X+051642Y+008648               S0      
317P12V             VIA        MD0160PA00X+051922Y+016091               S0      
317P12V             VIA        MD0160PA00X+051922Y+016511               S0      
317P12V             VIA        MD0160PA00X+052351Y+017097               S0      
317P12V             VIA        MD0160PA00X+052351Y+017517               S0      
317P12V             VIA        MD0160PA00X+052771Y+017097               S0      
317P12V             VIA        MD0160PA00X+052771Y+017517               S0      
317P12V             VIA        MD0160PA00X+053188Y+016132               S0      
317P12V             VIA        MD0160PA00X+053188Y+016552               S0      
317P12V             VIA        MD0160PA00X+053608Y+016132               S0      
317P12V             VIA        MD0160PA00X+053608Y+016552               S0      
317P12V             VIA        MD0160PA00X+053642Y+010648               S0      
317P12V             VIA        MD0160PA00X+053642Y+012648               S0      
317P12V             VIA        MD0160PA00X+053642Y+014648               S0      
317P12V             VIA        MD0160PA00X+053642Y+006648               S0      
317P12V             VIA        MD0160PA00X+053642Y+008648               S0      
317P12V             VIA        MD0160PA00X+054028Y+016132               S0      
317P12V             VIA        MD0160PA00X+054028Y+016552               S0      
317P12V             VIA        MD0160PA00X+054448Y+016132               S0      
317P12V             VIA        MD0160PA00X+054448Y+016552               S0      
317P12V             VIA        MD0160PA00X+054872Y+017092               S0      
317P12V             VIA        MD0160PA00X+054872Y+017512               S0      
317P12V             VIA        MD0160PA00X+055292Y+017092               S0      
317P12V             VIA        MD0160PA00X+055292Y+017512               S0      
317P12V             VIA        MD0160PA00X+055642Y+010648               S0      
317P12V             VIA        MD0160PA00X+055642Y+012648               S0      
317P12V             VIA        MD0160PA00X+055642Y+014648               S0      
317P12V             VIA        MD0160PA00X+055642Y+008648               S0      
317P12V             VIA        MD0160PA00X+005642Y+010648               S0      
317P12V             VIA        MD0160PA00X+005642Y+012648               S0      
317P12V             VIA        MD0160PA00X+005642Y+014648               S0      
317P12V             VIA        MD0160PA00X+005642Y+016648               S0      
317P12V             VIA        MD0160PA00X+005642Y+018648               S0      
317P12V             VIA        MD0160PA00X+005642Y+006648               S0      
317P12V             VIA        MD0160PA00X+005642Y+008648               S0      
317P12V             VIA        MD0160PA00X+057642Y+010648               S0      
317P12V             VIA        MD0160PA00X+057642Y+012648               S0      
317P12V             VIA        MD0160PA00X+000642Y+011648               S0      
317P12V             VIA        MD0160PA00X+000642Y+012648               S0      
317P12V             VIA        MD0160PA00X+000642Y+013648               S0      
317P12V             VIA        MD0160PA00X+000642Y+014648               S0      
317P12V             VIA        MD0160PA00X+000642Y+015648               S0      
317P12V             VIA        MD0160PA00X+000642Y+016648               S0      
317P12V             VIA        MD0160PA00X+000642Y+017648               S0      
317P12V             VIA        MD0160PA00X+007642Y+010648               S0      
317P12V             VIA        MD0160PA00X+007642Y+012648               S0      
317P12V             VIA        MD0160PA00X+007642Y+014648               S0      
317P12V             VIA        MD0160PA00X+007642Y+016648               S0      
317P12V             VIA        MD0160PA00X+007642Y+018648               S0      
317P12V             VIA        MD0160PA00X+007642Y+006648               S0      
317P12V             VIA        MD0160PA00X+007642Y+008648               S0      
317P12V             VIA        MD0160PA00X+009642Y+010648               S0      
317P12V             VIA        MD0160PA00X+009642Y+012648               S0      
317P12V             VIA        MD0160PA00X+009642Y+014648               S0      
317P12V             VIA        MD0160PA00X+009642Y+016648               S0      
317P12V             VIA        MD0160PA00X+009642Y+018648               S0      
317P12V             VIA        MD0160PA00X+009642Y+006648               S0      
317P12V             VIA        MD0160PA00X+009642Y+008648               S0      
317I2C_C_SDA                    D0220PA01X+003351Y+037413               S0      
317I2C_C_SDA                    D0220PA01X+004316Y+037389               S0      
317I2C_C_SDA                    D0220PA01X+006615Y+037398               S0      
317I2C_C_SDA                    D0340PA01X+003813Y+037433               S0      
317I2C_C_SDA        VIA        MD0280PA01X+002818Y+037900               S0      
317I2C_C_SCL                    D0220PA01X+004307Y+036925               S0      
317I2C_C_SCL                    D0220PA01X+006610Y+036947               S0      
317I2C_C_SCL                    D0340PA01X+003811Y+036873               S0      
317I2C_C_SCL                    D0220PA01X+003351Y+036893               S0      
317I2C_C_SCL        VIA        MD0280PA01X+002818Y+036406               S0      
317NNAME00000                   D0220PA01X+053773Y+026397               S0      
317NNAME00000                   D0340PA01X+054250Y+026377               S0      
317NNAME00000                   D0410PA00X+060071Y+022441               S0      
317NNAME00000       VIA        MD0280PA01X+054842Y+026297               S0      
317NNAME00001                   D0220PA01X+053773Y+026897               S0      
317NNAME00001                   D0410PA00X+060071Y+020441               S0      
317NNAME00001                   D0340PA01X+054250Y+026917               S0      
317NNAME00001       VIA        MD0280PA01X+054842Y+026977               S0      
317PWM_EXP_B_OUT                D0220PA01X+003860Y+033794               S0      
317PWM_EXP_B_OUT                D0410PA00X+060071Y+024441               S0      
317PWM_EXP_B_OUT    VIA        MD0280PA01X+043959Y+032162               S0      
317PWM_EXP_A_OUT                D0220PA01X+003860Y+033344               S0      
317PWM_EXP_A_OUT                D0410PA00X+059071Y+021441               S0      
317PWM_EXP_A_OUT    VIA        MD0280PA01X+017676Y+031944               S0      
327SELF_1B&2B_HB                      A01X-002756Y+034720X1970Y0320     S0      
317SELF_1B&2B_HB                D0410PA00X+059071Y+023441               S0      
317SELF_1B&2B_HB    VIA        MD0280PA01X+022872Y+031509               S0      
317TPS2490_EN1                  D0360PA00X+059118Y+043307               S0      
317TPS2490_EN1                  D0410PA00X+058071Y+020441               S0      
317TPS2490_EN1                  D0220PA01X+054800Y+043270               S0      
317TPS2490_EN1      VIA        MD0280PA04X+048704Y+034024               S0      
317TPS2490_EN1      VIA        MD0160PA00X+048550Y+037550               S0      
317TPS2490_EN2                  D0360PA00X+058134Y+043307               S0      
317TPS2490_EN2                  D0410PA00X+058071Y+021441               S0      
317TPS2490_EN2                  D0220PA01X+054800Y+042930               S0      
317TPS2490_EN2      VIA        MD0280PA04X+048950Y+035220               S0      
317TPS2490_EN2      VIA        MD0160PA00X+048950Y+037550               S0      
327SELF_1A&2A_HB                      A01X-002756Y+035220X1970Y0320     S0      
317SELF_1A&2A_HB                D0410PA00X+058071Y+022441               S0      
317SELF_1A&2A_HB    VIA        MD0280PA01X+026468Y+031727               S0      
327PEER_1A&2A_HB                      A01X-002756Y+032220X1970Y0320     S0      
317PEER_1A&2A_HB                D0410PA00X+058071Y+023441               S0      
317PEER_1A&2A_HB    VIA        MD0280PA01X+019629Y+030204               S0      
317PEER_1A&2A_HB    VIA        MD0160PA00X+056150Y+023200               S0      
327PEER_1B&2B_HB                      A01X-002756Y+031720X1970Y0320     S0      
317PEER_1B&2B_HB                D0410PA00X+058071Y+024441               S0      
317PEER_1B&2B_HB    VIA        MD0280PA01X+046326Y+029987               S0      
317PEER_1B&2B_HB    VIA        MD0160PA00X+055700Y+023150               S0      
327NNAME00002                         A04X-002756Y+031720X1970Y0320     S0      
317NNAME00002                   D0410PA00X+057071Y+020441               S0      
317NNAME00002       VIA        MD0280PA01X+013506Y+030422               S0      
317NNAME00002       VIA        MD0160PA00X+000340Y+032694               S0      
327TRAY_ID                            A01X-002756Y+034220X1970Y0320     S0      
317TRAY_ID                      D0410PA00X+057071Y+021441               S0      
317TRAY_ID          VIA        MD0280PA01X+031099Y+031074               S0      
327FCB_HW_REV                         A01X-002756Y+033720X1970Y0320     S0      
317FCB_HW_REV                   D0410PA00X+057071Y+022441               S0      
317FCB_HW_REV       VIA        MD0280PA01X+043941Y+030857               S0      
327NNAME00003                         A01X-002756Y+033220X1970Y0320     S0      
317NNAME00003                   D0410PA00X+057071Y+023441               S0      
317NNAME00003       VIA        MD0280PA01X+040156Y+030639               S0      
327NNAME00004                         A04X-002756Y+032720X1970Y0320     S0      
317NNAME00004                   D0300PA01X+052901Y+029326               S0      
317NNAME00004                   D0220PA01X+053800Y+029330               S0      
317NNAME00004                   D0410PA00X+057071Y+024441               S0      
317NNAME00004       VIA        MD0280PA01X+035809Y+031292               S0      
317NNAME00004       VIA        MD0160PA00X+001000Y+033200               S0      
327PWM_EXP_B                          A04X-002756Y+032220X1970Y0320     S0      
317PWM_EXP_B                    D0220PA01X+003520Y+033794               S0      
317PWM_EXP_B        VIA        MD0280PA04X+002650Y+033044               S0      
317PWM_EXP_B        VIA        MD0160PA00X+003092Y+033567               S0      
317PWM_EXP_A                    D0220PA01X+003520Y+033344               S0      
327PWM_EXP_A                          A04X-002756Y+033220X1970Y0320     S0      
317PWM_EXP_A        VIA        MD0280PA04X+001400Y+033600               S0      
317PWM_EXP_A        VIA        MD0160PA00X+002672Y+033567               S0      
317NNAME00005                   D0220PA01X+003011Y+037413               S0      
327NNAME00005                         A04X-002756Y+034220X1970Y0320     S0      
317NNAME00005       VIA        MD0280PA04X-000272Y+034100               S0      
317NNAME00005       VIA        MD0160PA00X+000149Y+034371               S0      
327NNAME00006                         A04X-002756Y+035220X1970Y0320     S0      
317NNAME00006                   D0220PA01X+003011Y+036893               S0      
317NNAME00006       VIA        MD0280PA04X+000164Y+034776               S0      
317NNAME00006       VIA        MD0160PA00X+000569Y+034371               S0      
317P5VA                         D0340PA01X+061780Y+040874               S0      
327P5VA                               A01X-002756Y+030220X1970Y0320     S0      
317P5VA             VIA        MD0280PA04X+002090Y+032544               S0      
317P5VA             VIA        MD0280PA04X+053640Y+041894               S0      
317P5VA             VIA        MD0160PA00X+000233Y+031865               S0      
317P5VA             VIA        MD0160PA00X+061780Y+041300               S0      
317TPS2490_LED                  D0340PA01X+061800Y+007170               S0      
317TPS2490_LED                  D0340PA01X+063449Y+007200               S0      
317TPS2490_LED      VIA        MD0280PA01X+062350Y+007150               S0      
327EMITTER_K                          A01X+055050Y+032994X0550Y0450     S0      
327EMITTER_K                          A01X+061857Y+034380X0740Y1220     S0      
317EMITTER_K        VIA        MD0280PA01X+062260Y+033174               S0      
317DETECTOR_C                   D0340PA01X+061780Y+040314               S0      
327DETECTOR_C                         A01X+061857Y+038750X0740Y1220     S0      
317DETECTOR_C                   D0340PA01X+061280Y+040304               S0      
317DETECTOR_C       VIA        MD0280PA01X+062490Y+040094               S0      
327IR_SWITCH_E                        A01X+060710Y+038750X0740Y1220     S0      
317IR_SWITCH_E                  D0220PA01X+053354Y+033490               S0      
317IR_SWITCH_E      VIA        MD0280PA01X+052900Y+035350               S0      
317NNAME00007                   D0300PA01X+053291Y+031585               S0      
317NNAME00007                   D0220PA01X+053364Y+032210               S0      
317NNAME00007       VIA        MD0280PA01X+053794Y+032210               S0      
317NNAME00008                   D0300PA01X+052904Y+030835               S0      
317NNAME00008                   D0220PA01X+052620Y+032200               S0      
317NNAME00008                   D0220PA01X+052620Y+032600               S0      
317NNAME00008       VIA        MD0280PA01X+052489Y+033023               S0      
317TRAY_MOSFET_G                D0220PA01X+052280Y+032200               S0      
317TRAY_MOSFET_G                D0300PA01X+053289Y+030076               S0      
317TRAY_MOSFET_G                D0220PA01X+053354Y+033060               S0      
317TRAY_MOSFET_G    VIA        MD0280PA01X+054074Y+030990               S0      
317NNAME00009                   D0220PA01X+004307Y+036585               S0      
327NNAME00009                         A01X+005246Y+036335X0160Y0600     S0      
317NNAME00009                   D0220PA01X+005271Y+035580               S0      
317NNAME00009       VIA        MD0280PA01X+004307Y+036053               S0      
317I2C_C_BUF_EN                 D0220PA01X+004833Y+035585               S0      
327I2C_C_BUF_EN                       A01X+004990Y+036335X0160Y0600     S0      
317I2C_C_BUF_EN     VIA        MD0280PA01X+004304Y+035367               S0      
317NNAME00010                   D0220PA01X+005109Y+038733               S0      
327NNAME00010                         A01X+005246Y+037965X0160Y0600     S0      
317NNAME00010                   D0220PA01X+004316Y+037729               S0      
317NNAME00010       VIA        MD0280PA01X+004316Y+038261               S0      
327NNAME00011                         A01X+005758Y+037965X0160Y0600     S0      
317NNAME00011                   D0220PA01X+006005Y+038729               S0      
317NNAME00011                   D0320PA01X+006741Y+039126               S0      
317NNAME00012                   D0220PA01X+053014Y+033060               S0      
317NNAME00012                   D0220PA01X+053024Y+032210               S0      
317NNAME00012                   D0220PA01X+053014Y+033490               S0      
317NNAME00012                   D0220PA01X+053024Y+032640               S0      
317NNAME00012       VIA        MD0280PA01X+052627Y+033818               S0      
327NNAME00013                         A01X+005502Y+036335X0160Y0600     S0      
317NNAME00013                   D0220PA01X+006609Y+036516               S0      
317NNAME00013                   D0220PA01X+005740Y+035586               S0      
317NNAME00013       VIA        MD0280PA01X+006604Y+035989               S0      
317NNAME00014                   D0220PA01X+005535Y+038737               S0      
327NNAME00014                         A01X+005502Y+037965X0160Y0600     S0      
317NNAME00014                   D0220PA01X+006615Y+037824               S0      
317NNAME00014       VIA        MD0280PA01X+006610Y+038351               S0      
317I2C_C_BUF_SDA                D0220PA01X+053433Y+026897               S0      
317I2C_C_BUF_SDA                D0220PA01X+006955Y+037824               S0      
317I2C_C_BUF_SDA                D0220PA01X+006955Y+037398               S0      
317I2C_C_BUF_SDA    VIA        MD0280PA01X+008100Y+037279               S0      
317I2C_C_BUF_SCL                D0220PA01X+053433Y+026397               S0      
317I2C_C_BUF_SCL                D0220PA01X+006950Y+036947               S0      
317I2C_C_BUF_SCL                D0220PA01X+006949Y+036516               S0      
317I2C_C_BUF_SCL    VIA        MD0280PA01X+007480Y+036947               S0      
317NNAME00015                   D0360PA00X+057150Y+043307               S0      
317NNAME00015                   D0220PA01X+054770Y+041900               S0      
999
